FILE_TYPE = CONNECTIVITY;
{Allegro Design Entry HDL 17.2-2016 S081 (4005846) 1/11/2022}
"PAGE_NUMBER" = 59;
0"NC";
%"ME_DUMMY_SYMBOL"
"1","(-3125,4675)","0","pure_quanta","I27";
;
MATERIAL"EMPTY"
PART_NUMBER"DUMMY1"
PART_TYPE"MECH"
VALUE"QUANTA_LOGO_7X26"
CDS_LMAN_SYM_OUTLINE"-200,125,200,-125"
NEEDS_NO_SIZE"TRUE"
PIN_TEXT_VISIBLE"True"
PIN_NAMES_ROTATE"True"
CDS_LIB"pure_quanta"
$LOCATION"ME1"
CDS_LOCATION"ME1";
%"ME_DUMMY_SYMBOL"
"1","(-1875,4650)","0","pure_quanta","I28";
;
VALUE"WEEE"
PART_NUMBER"DUMMY2"
MATERIAL"EMPTY"
PART_TYPE"MECH"
CDS_LMAN_SYM_OUTLINE"-200,125,200,-125"
NEEDS_NO_SIZE"TRUE"
PIN_TEXT_VISIBLE"True"
PIN_NAMES_ROTATE"True"
CDS_LIB"pure_quanta"
$LOCATION"ME2"
CDS_LOCATION"ME2";
%"ME_DUMMY_SYMBOL"
"1","(-350,4600)","0","pure_quanta","I29";
;
VALUE"PB-E1_SMALL"
PART_TYPE"MECH"
PART_NUMBER"DUMMY3"
MATERIAL"EMPTY"
CDS_LMAN_SYM_OUTLINE"-200,125,200,-125"
NEEDS_NO_SIZE"TRUE"
PIN_TEXT_VISIBLE"True"
PIN_NAMES_ROTATE"True"
CDS_LIB"pure_quanta"
LOCATION"DM7";
%"ME_DUMMY_SYMBOL"
"1","(5150,1975)","0","pure_quanta","I34";
;
PART_TYPE"MECH"
PART_NUMBER"DUMMY69"
MATERIAL"EMPTY"
VALUE"SNLABEL_7X7"
PIN_NAMES_ROTATE"True"
PIN_TEXT_VISIBLE"True"
NEEDS_NO_SIZE"TRUE"
CDS_LMAN_SYM_OUTLINE"-200,125,200,-125"
CDS_LIB"pure_quanta"
$LOCATION"ME4"
CDS_LOCATION"ME4";
%"DUMMY_SYMBOL"
"1","(-1600,3325)","0","pure_quanta","I35";
;
MATERIAL"MECH"
PART_TYPE"MECH"
PART_NUMBER"DUMMY9"
VALUE"BIOS_FLASH"
CDS_LIB"pure_quanta"
CDS_LMAN_SYM_OUTLINE"-200,75,200,-75"
PIN_NAMES_ROTATE"True"
$LOCATION"DM3"
CDS_LOCATION"DM3"
$SEC"1"
CDS_SEC"1";
"1"
$PN"1"0;
%"DUMMY_SYMBOL"
"1","(-3200,3250)","0","pure_quanta","I36";
;
PART_NUMBER"DUMMY8"
VALUE"BMC_FLASH"
PART_TYPE"MECH"
MATERIAL"EMPTY"
CDS_LMAN_SYM_OUTLINE"-200,75,200,-75"
PIN_NAMES_ROTATE"True"
CDS_LIB"pure_quanta"
$LOCATION"DM1"
CDS_LOCATION"DM1"
$SEC"1"
CDS_SEC"1";
"1"
$PN"1"0;
%"DUMMY_SYMBOL"
"1","(-2675,3250)","0","pure_quanta","I37";
;
PART_TYPE"MECH"
PART_NUMBER"DUMMY8"
MATERIAL"EMPTY"
VALUE"BMC_FLASH"
CDS_LIB"pure_quanta"
PIN_NAMES_ROTATE"True"
CDS_LMAN_SYM_OUTLINE"-200,75,200,-75"
$LOCATION"DM2"
CDS_LOCATION"DM2"
$SEC"1"
CDS_SEC"1";
"1"
$PN"1"0;
END.
